(kicad_pcb
	(version 20241229)
	(generator "pcbnew")
	(generator_version "9.0")
	(general
		(thickness 1.711)
		(legacy_teardrops no)
	)
	(paper "A4")
	(title_block
		(title "Antmicro Baseboard for Jetson AGX Thor")
		(date "2026-02-18")
		(rev "1.1.0")
		(company "Antmicro Ltd")
		(comment 1 "www.antmicro.com")
		(comment 9 "footprints 534-537 of 1170")
	)
	(layers
		(0 "F.Cu" signal)
		(4 "In1.Cu" signal)
		(6 "In2.Cu" signal)
		(8 "In3.Cu" signal)
		(10 "In4.Cu" jumper)
		(12 "In5.Cu" signal)
		(14 "In6.Cu" signal)
		(16 "In7.Cu" signal)
		(18 "In8.Cu" signal)
		(2 "B.Cu" signal)
		(9 "F.Adhes" user "F.Adhesive")
		(11 "B.Adhes" user "B.Adhesive")
		(13 "F.Paste" user)
		(15 "B.Paste" user)
		(5 "F.SilkS" user "F.Silkscreen")
		(7 "B.SilkS" user "B.Silkscreen")
		(1 "F.Mask" user)
		(3 "B.Mask" user)
		(17 "Dwgs.User" user "User.Drawings")
		(19 "Cmts.User" user "User.Comments")
		(21 "Eco1.User" user "User.Eco1")
		(23 "Eco2.User" user "User.Eco2")
		(25 "Edge.Cuts" user)
		(27 "Margin" user)
		(31 "F.CrtYd" user "F.Courtyard")
		(29 "B.CrtYd" user "B.Courtyard")
		(35 "F.Fab" user)
		(33 "B.Fab" user)
	)
	(footprint "antmicro-footprints:R_0402_1005Metric"
		(layer "F.Cu")
		(at 94 59.5 180)
		(descr "Resistor SMD 0402")
		(tags "resistor SMD 0402")
		(property "Reference" "R308"
			(at -9.7 -0.8 0)
			(layer "F.SilkS")
			(effects
				(font
					(size 0.7 0.7)
					(thickness 0.15)
				)
				(justify right top)
			)
		)
		(property "Value" "R_100k_0402"
			(at -1.011843 1.772047 0)
			(layer "F.Fab")
			(effects
				(font
					(size 0.7 0.7)
					(thickness 0.15)
				)
				(justify right top)
			)
		)
		(property "Datasheet" "https://www.bourns.com/docs/product-datasheets/cr.pdf"
			(at 0 0 0)
			(layer "F.Fab")
			(hide yes)
			(effects
				(font
					(size 1.27 1.27)
					(thickness 0.15)
				)
			)
		)
		(property "Description" "SMD Chip Resistor, 100 kohm, ± 1%, 62.5 mW, 0402 [1005 Metric], Thick Film, General Purpose"
			(at 0 0 0)
			(layer "F.Fab")
			(hide yes)
			(effects
				(font
					(size 1.27 1.27)
					(thickness 0.15)
				)
			)
		)
		(property "MPN" "CR0402-FX-1003GLF"
			(at 0 0 180)
			(unlocked yes)
			(layer "F.Fab")
			(hide yes)
			(effects
				(font
					(size 1 1)
					(thickness 0.15)
				)
			)
		)
		(property "Manufacturer" "Bourns"
			(at 0 0 180)
			(unlocked yes)
			(layer "F.Fab")
			(hide yes)
			(effects
				(font
					(size 1 1)
					(thickness 0.15)
				)
			)
		)
		(property "License" "Apache-2.0"
			(at 0 0 180)
			(unlocked yes)
			(layer "F.Fab")
			(hide yes)
			(effects
				(font
					(size 1 1)
					(thickness 0.15)
				)
			)
		)
		(property "Author" "Antmicro"
			(at 0 0 180)
			(unlocked yes)
			(layer "F.Fab")
			(hide yes)
			(effects
				(font
					(size 1 1)
					(thickness 0.15)
				)
			)
		)
		(property "Val" "100k"
			(at 0 0 180)
			(unlocked yes)
			(layer "F.Fab")
			(hide yes)
			(effects
				(font
					(size 1 1)
					(thickness 0.15)
				)
			)
		)
		(property "Tolerance" "1%"
			(at 0 0 180)
			(unlocked yes)
			(layer "F.Fab")
			(hide yes)
			(effects
				(font
					(size 1 1)
					(thickness 0.15)
				)
			)
		)
		(property "Public" "False"
			(at 0 0 180)
			(unlocked yes)
			(layer "F.Fab")
			(hide yes)
			(effects
				(font
					(size 1 1)
					(thickness 0.15)
				)
			)
		)
		(sheetname "/SoM_Power/")
		(sheetfile "som_power.kicad_sch")
		(attr smd exclude_from_pos_files exclude_from_bom dnp)
		(fp_rect
			(start -0.925 -0.47)
			(end 0.925 0.47)
			(stroke
				(width 0.05)
				(type default)
			)
			(fill no)
			(layer "F.CrtYd")
		)
		(fp_rect
			(start -0.5 -0.25)
			(end 0.5 0.25)
			(stroke
				(width 0.15)
				(type solid)
			)
			(fill no)
			(layer "F.Fab")
		)
		(fp_text user "License: Apache-2.0"
			(at -0.95 5.169 0)
			(layer "F.Fab")
			(effects
				(font
					(size 0.7 0.7)
					(thickness 0.15)
				)
				(justify right top)
			)
		)
		(fp_text user "${REFERENCE}"
			(at -0.95 3.168 0)
			(layer "F.Fab")
			(effects
				(font
					(size 0.7 0.7)
					(thickness 0.15)
				)
				(justify right top)
			)
		)
		(fp_text user "Author: Antmicro"
			(at -0.95 4.169 0)
			(layer "F.Fab")
			(effects
				(font
					(size 0.7 0.7)
					(thickness 0.15)
				)
				(justify right top)
			)
		)
		(pad "1" smd roundrect
			(at -0.48 0 180)
			(size 0.59 0.64)
			(layers "F.Cu" "F.Mask" "F.Paste")
			(roundrect_rratio 0.25)
			(net 524 "Net-(Q22-D)")
			(pintype "passive")
		)
		(pad "2" smd roundrect
			(at 0.48 0 180)
			(size 0.59 0.64)
			(layers "F.Cu" "F.Mask" "F.Paste")
			(roundrect_rratio 0.25)
			(net 610 "/SoM_Power/~{PWR_BTN}")
			(pintype "passive")
		)
	)
	(footprint "antmicro-footprints:Fiducial_1mm_Mask3mm"
		(layer "F.Cu")
		(at 82.5 151.47)
		(descr "Circular Fiducial, 1.5mm bare copper, 3mm soldermask opening")
		(tags "fiducial")
		(property "Reference" "FD2"
			(at 1.09 1.74 0)
			(layer "F.SilkS")
			(effects
				(font
					(size 0.7 0.7)
					(thickness 0.15)
				)
				(justify left bottom)
			)
		)
		(property "Value" "Fiducial_1mm_Mask3mm"
			(at 0 2.603 0)
			(layer "F.Fab")
			(effects
				(font
					(size 0.7 0.7)
					(thickness 0.15)
				)
				(justify left bottom)
			)
		)
		(property "Description" "Fiducial mask"
			(at 0 0 0)
			(layer "F.Fab")
			(hide yes)
			(effects
				(font
					(size 1.27 1.27)
					(thickness 0.15)
				)
			)
		)
		(property "Author" "Antmicro"
			(at 0 0 0)
			(unlocked yes)
			(layer "F.Fab")
			(hide yes)
			(effects
				(font
					(size 1 1)
					(thickness 0.15)
				)
			)
		)
		(property "License" "Apache-2.0"
			(at 0 0 0)
			(unlocked yes)
			(layer "F.Fab")
			(hide yes)
			(effects
				(font
					(size 1 1)
					(thickness 0.15)
				)
			)
		)
		(sheetname "/")
		(sheetfile "jetson-agx-thor-baseboard.kicad_sch")
		(attr exclude_from_pos_files exclude_from_bom)
		(fp_circle
			(center 0 0)
			(end 1.5 0)
			(stroke
				(width 0.05)
				(type solid)
			)
			(fill no)
			(layer "F.CrtYd")
		)
		(fp_circle
			(center 0 0)
			(end 1.5 0)
			(stroke
				(width 0.15)
				(type solid)
			)
			(fill no)
			(layer "F.Fab")
		)
		(fp_text user "Author: Antmicro"
			(at -1.25 5.803 0)
			(layer "F.Fab")
			(effects
				(font
					(size 0.7 0.7)
					(thickness 0.15)
				)
				(justify left bottom)
			)
		)
		(fp_text user "${REFERENCE}"
			(at -1.25 4.603 0)
			(layer "F.Fab")
			(effects
				(font
					(size 0.7 0.7)
					(thickness 0.15)
				)
				(justify left bottom)
			)
		)
		(fp_text user "License: Apache-2.0"
			(at -1.25 7.003 0)
			(layer "F.Fab")
			(effects
				(font
					(size 0.7 0.7)
					(thickness 0.15)
				)
				(justify left bottom)
			)
		)
		(pad "" smd circle
			(at 0 0)
			(size 1 1)
			(layers "F.Cu" "F.Mask")
			(solder_mask_margin 1)
			(clearance 1)
		)
	)
	(footprint "antmicro-footprints:R_0402_1005Metric"
		(layer "F.Cu")
		(at 106.850001 57.68)
		(descr "Resistor SMD 0402")
		(tags "resistor SMD 0402")
		(property "Reference" "R314"
			(at -2.730001 6.11 0)
			(layer "F.SilkS")
			(effects
				(font
					(size 0.7 0.7)
					(thickness 0.15)
				)
				(justify left bottom)
			)
		)
		(property "Value" "R_27R_0402"
			(at -1.011843 1.772046 0)
			(layer "F.Fab")
			(effects
				(font
					(size 0.7 0.7)
					(thickness 0.15)
				)
				(justify left bottom)
			)
		)
		(property "Datasheet" "https://www.bourns.com/docs/product-datasheets/cr.pdf"
			(at 0 0 0)
			(layer "F.Fab")
			(hide yes)
			(effects
				(font
					(size 1.27 1.27)
					(thickness 0.15)
				)
			)
		)
		(property "Description" "SMD Chip Resistor, 27 ohm, ± 1%, 63 mW, 0402 [1005 Metric], Thick Film, General Purpose"
			(at 0 0 0)
			(layer "F.Fab")
			(hide yes)
			(effects
				(font
					(size 1.27 1.27)
					(thickness 0.15)
				)
			)
		)
		(property "MPN" "CR0402-FX-27R0GLF"
			(at 0 0 0)
			(unlocked yes)
			(layer "F.Fab")
			(hide yes)
			(effects
				(font
					(size 1 1)
					(thickness 0.15)
				)
			)
		)
		(property "Manufacturer" "Bourns"
			(at 0 0 0)
			(unlocked yes)
			(layer "F.Fab")
			(hide yes)
			(effects
				(font
					(size 1 1)
					(thickness 0.15)
				)
			)
		)
		(property "License" "Apache-2.0"
			(at 0 0 0)
			(unlocked yes)
			(layer "F.Fab")
			(hide yes)
			(effects
				(font
					(size 1 1)
					(thickness 0.15)
				)
			)
		)
		(property "Author" "Antmicro"
			(at 0 0 0)
			(unlocked yes)
			(layer "F.Fab")
			(hide yes)
			(effects
				(font
					(size 1 1)
					(thickness 0.15)
				)
			)
		)
		(property "Val" "27R"
			(at 0 0 0)
			(unlocked yes)
			(layer "F.Fab")
			(hide yes)
			(effects
				(font
					(size 1 1)
					(thickness 0.15)
				)
			)
		)
		(property "Tolerance" "1%"
			(at 0 0 0)
			(unlocked yes)
			(layer "F.Fab")
			(hide yes)
			(effects
				(font
					(size 1 1)
					(thickness 0.15)
				)
			)
		)
		(sheetname "/DCDC/")
		(sheetfile "dcdc.kicad_sch")
		(attr smd)
		(fp_poly
			(pts
				(xy -0.925 -0.47) (xy -0.925 0.47) (xy 0.925 0.47) (xy 0.925 -0.47)
			)
			(stroke
				(width 0.05)
				(type default)
			)
			(fill no)
			(layer "F.CrtYd")
		)
		(fp_poly
			(pts
				(xy -0.5 -0.25) (xy -0.5 0.25) (xy 0.5 0.25) (xy 0.5 -0.25)
			)
			(stroke
				(width 0.15)
				(type solid)
			)
			(fill no)
			(layer "F.Fab")
		)
		(fp_text user "Author: Antmicro"
			(at -0.95 4.169 0)
			(layer "F.Fab")
			(effects
				(font
					(size 0.7 0.7)
					(thickness 0.15)
				)
				(justify left bottom)
			)
		)
		(fp_text user "License: Apache-2.0"
			(at -0.949999 5.169 0)
			(layer "F.Fab")
			(effects
				(font
					(size 0.7 0.7)
					(thickness 0.15)
				)
				(justify left bottom)
			)
		)
		(fp_text user "${REFERENCE}"
			(at -0.95 3.168 0)
			(layer "F.Fab")
			(effects
				(font
					(size 0.7 0.7)
					(thickness 0.15)
				)
				(justify left bottom)
			)
		)
		(pad "1" smd roundrect
			(at -0.48 0)
			(size 0.59 0.64)
			(layers "F.Cu" "F.Mask" "F.Paste")
			(roundrect_rratio 0.25)
			(net 1280 "Net-(U76-IN+)")
			(pintype "passive")
		)
		(pad "2" smd roundrect
			(at 0.48 0)
			(size 0.59 0.64)
			(layers "F.Cu" "F.Mask" "F.Paste")
			(roundrect_rratio 0.25)
			(net 1278 "/DCDC/5V_{AON}_OUT")
			(pintype "passive")
		)
	)
	(footprint "antmicro-footprints:R_0402_1005Metric"
		(layer "F.Cu")
		(at 74.5 76.85 90)
		(descr "Resistor SMD 0402")
		(tags "resistor SMD 0402")
		(property "Reference" "R349"
			(at -0.95 -0.7 90)
			(layer "F.SilkS")
			(effects
				(font
					(size 0.7 0.7)
					(thickness 0.15)
				)
				(justify left bottom)
			)
		)
		(property "Value" "R_10k_0402"
			(at -1.011843 1.772046 90)
			(layer "F.Fab")
			(effects
				(font
					(size 0.7 0.7)
					(thickness 0.15)
				)
				(justify left bottom)
			)
		)
		(property "Datasheet" "https://www.bourns.com/docs/product-datasheets/cr.pdf"
			(at 0 0 90)
			(layer "F.Fab")
			(hide yes)
			(effects
				(font
					(size 1.27 1.27)
					(thickness 0.15)
				)
			)
		)
		(property "Description" "SMD Chip Resistor, 10 kohm, ± 1%, 62.5 mW, 0402 [1005 Metric], Thick Film, General Purpose"
			(at 0 0 90)
			(layer "F.Fab")
			(hide yes)
			(effects
				(font
					(size 1.27 1.27)
					(thickness 0.15)
				)
			)
		)
		(property "MPN" "CR0402-FX-1002GLF"
			(at 0 0 90)
			(unlocked yes)
			(layer "F.Fab")
			(hide yes)
			(effects
				(font
					(size 1 1)
					(thickness 0.15)
				)
			)
		)
		(property "Manufacturer" "Bourns"
			(at 0 0 90)
			(unlocked yes)
			(layer "F.Fab")
			(hide yes)
			(effects
				(font
					(size 1 1)
					(thickness 0.15)
				)
			)
		)
		(property "License" "Apache-2.0"
			(at 0 0 90)
			(unlocked yes)
			(layer "F.Fab")
			(hide yes)
			(effects
				(font
					(size 1 1)
					(thickness 0.15)
				)
			)
		)
		(property "Author" "Antmicro"
			(at 0 0 90)
			(unlocked yes)
			(layer "F.Fab")
			(hide yes)
			(effects
				(font
					(size 1 1)
					(thickness 0.15)
				)
			)
		)
		(property "Val" "10k"
			(at 0 0 90)
			(unlocked yes)
			(layer "F.Fab")
			(hide yes)
			(effects
				(font
					(size 1 1)
					(thickness 0.15)
				)
			)
		)
		(property "Tolerance" "1%"
			(at 0 0 90)
			(unlocked yes)
			(layer "F.Fab")
			(hide yes)
			(effects
				(font
					(size 1 1)
					(thickness 0.15)
				)
			)
		)
		(sheetname "/Expansion connector/")
		(sheetfile "expansion_connector.kicad_sch")
		(attr smd)
		(fp_poly
			(pts
				(xy -0.925 -0.47) (xy 0.925 -0.47) (xy 0.925 0.47) (xy -0.925 0.47)
			)
			(stroke
				(width 0.05)
				(type default)
			)
			(fill no)
			(layer "F.CrtYd")
		)
		(fp_poly
			(pts
				(xy -0.5 -0.25) (xy 0.5 -0.25) (xy 0.5 0.25) (xy -0.5 0.25)
			)
			(stroke
				(width 0.15)
				(type solid)
			)
			(fill no)
			(layer "F.Fab")
		)
		(fp_text user "License: Apache-2.0"
			(at -0.949999 5.169 90)
			(layer "F.Fab")
			(effects
				(font
					(size 0.7 0.7)
					(thickness 0.15)
				)
				(justify left bottom)
			)
		)
		(fp_text user "Author: Antmicro"
			(at -0.95 4.169 90)
			(layer "F.Fab")
			(effects
				(font
					(size 0.7 0.7)
					(thickness 0.15)
				)
				(justify left bottom)
			)
		)
		(fp_text user "${REFERENCE}"
			(at -0.95 3.168 90)
			(layer "F.Fab")
			(effects
				(font
					(size 0.7 0.7)
					(thickness 0.15)
				)
				(justify left bottom)
			)
		)
		(pad "1" smd roundrect
			(at -0.48 0 90)
			(size 0.59 0.64)
			(layers "F.Cu" "F.Mask" "F.Paste")
			(roundrect_rratio 0.25)
			(net 319 "/Expansion connector/FMC_PRSNT_M2C_L")
			(pintype "passive")
		)
		(pad "2" smd roundrect
			(at 0.48 0 90)
			(size 0.59 0.64)
			(layers "F.Cu" "F.Mask" "F.Paste")
			(roundrect_rratio 0.25)
			(net 11 "+1V8")
			(pintype "passive")
		)
	)
)
